# S9S_MB_2U (Grand Teton) — schematic netlist excerpt (pin names and nets, part order shuffled) for the footprints in the layout excerpt that follows; sources: Cadence DE-HDL packaged netlist, KiCad conversion of 03242023_DA0F0TMBIJ0_F0T_Motherboard_J_brd_V01_OCP.brd

PU296  MP5991GLUZ  MP5991GLU-Z IC  pkg LGA32_TH_0-5_5X5  page 303
  VOUT1  = P12V_AUX
  VOUT2  = P12V_AUX
  D_OC  = HSC_D_OC_3
  \on\  = HSC_ON
  GOK  = HSC_FAULT
  FLT_TYPE  = HSC_FLT_TYPE_3
  NC1  = HSC_NC1_3
  MODE  = HSC_MODE_3
  VIN1  = P12V_PSU
  VIN2  = P12V_PSU
  VIN3  = P12V_PSU
  VIN4  = P12V_PSU
  VIN5  = P12V_PSU
  VIN6  = P12V_PSU
  VIN7  = P12V_PSU
  VIN8  = P12V_PSU
  SCREF_OCWREF  = HSC_SCREF_3
  VTEMP  = HSC_VTEMP
  SS  = HSC_SS
  GND  = AGND_HSC
  VDD33  = HSC_VDD_R_3
  IMON  = HSC_IMON
  CS  = HSC_CS_3
  OCREF  = HSC_OCREF
  VOUT3  = P12V_AUX
  VOUT4  = P12V_AUX
  VOUT5  = P12V_AUX
  VOUT6  = P12V_AUX
  VOUT7  = P12V_AUX
  VOUT8  = P12V_AUX
  VOUT9  = P12V_AUX
  VOUT10  = P12V_AUX
  VIN9  = P12V_PSU

(kicad_pcb
	(version 20260206)
	(generator "pcbnew")
	(generator_version "10.0")
	(general
		(thickness 1.6)
		(legacy_teardrops no)
	)
	(paper "A4")
	(title_block
		(title "03242023_DA0F0TMBIJ0_F0T_Motherboard_J_brd_V01_OCP.brd")
		(comment 1 "Grand Teton / footprints 2435-2435 of 6105")
	)
	(layers
		(0 "F.Cu" signal "TOP")
		(4 "In1.Cu" signal "GND")
		(6 "In2.Cu" signal "IN1")
		(8 "In3.Cu" signal "GND1")
		(10 "In4.Cu" signal "IN2")
		(12 "In5.Cu" signal "GND2")
		(14 "In6.Cu" signal "IN3")
		(16 "In7.Cu" signal "GND3")
		(18 "In8.Cu" signal "VCC")
		(20 "In9.Cu" signal "VCC1")
		(22 "In10.Cu" signal "GND4")
		(24 "In11.Cu" signal "IN4")
		(26 "In12.Cu" signal "GND5")
		(28 "In13.Cu" signal "IN5")
		(30 "In14.Cu" signal "GND6")
		(32 "In15.Cu" signal "IN6")
		(34 "In16.Cu" signal "GND7")
		(2 "B.Cu" signal "BOTTOM")
		(9 "F.Adhes" user "F.Adhesive")
		(11 "B.Adhes" user "B.Adhesive")
		(13 "F.Paste" user "Package Geometry/Pastemask Top")
		(15 "B.Paste" user "Package Geometry/Pastemask Bottom")
		(5 "F.SilkS" user "Ref Des/Silkscreen Top")
		(7 "B.SilkS" user "Ref Des/Silkscreen Bottom")
		(1 "F.Mask" user "Board Geometry/Soldermask Top")
		(3 "B.Mask" user "Board Geometry/Soldermask Bottom")
		(17 "Dwgs.User" user "User.Drawings")
		(19 "Cmts.User" user "User.Comments")
		(21 "Eco1.User" user "User.Eco1")
		(23 "Eco2.User" user "User.Eco2")
		(25 "Edge.Cuts" user "Board Geometry/Outline")
		(27 "Margin" user)
		(31 "F.CrtYd" user "Package Geometry/Place Bound Top")
		(29 "B.CrtYd" user "Package Geometry/Place Bound Bottom")
		(35 "F.Fab" user "Ref Des/Assembly Top")
		(33 "B.Fab" user "Ref Des/Assembly Bottom")
	)
	(footprint ""
		(layer "F.Cu")
		(at 221.508066 -402.722842 180)
		(property "Reference" "PU296"
			(at -0.222504 7.882128 0)
			(unlocked yes)
			(layer "F.SilkS")
			(effects
				(font
					(size 0.7874 0.5842)
					(thickness 0.1524)
				)
			)
		)
		(property "Value" ""
			(at 0 0 180)
			(layer "F.Fab")
			(effects
				(font
					(size 1.27 1.27)
				)
			)
		)
		(duplicate_pad_numbers_are_jumpers no)
		(fp_line
			(start 2.567686 2.567686)
			(end 2.567686 -2.567686)
			(stroke
				(width 0.1524)
				(type default)
			)
			(layer "F.SilkS")
		)
		(fp_line
			(start 2.567686 -2.567686)
			(end -2.567686 -2.567686)
			(stroke
				(width 0.1524)
				(type default)
			)
			(layer "F.SilkS")
		)
		(fp_line
			(start -2.567686 2.567686)
			(end 2.567686 2.567686)
			(stroke
				(width 0.1524)
				(type default)
			)
			(layer "F.SilkS")
		)
		(fp_line
			(start -2.567686 -2.567686)
			(end -2.567686 2.567686)
			(stroke
				(width 0.1524)
				(type default)
			)
			(layer "F.SilkS")
		)
		(fp_poly
			(pts
				(xy -3.1242 -3.37058) (xy -2.765044 -2.292858) (xy -3.842766 -2.652014)
			)
			(stroke
				(width 0)
				(type default)
			)
			(fill yes)
			(layer "F.SilkS")
		)
		(fp_line
			(start 2.549906 2.549906)
			(end 2.549906 -2.549906)
			(stroke
				(width 0.1)
				(type default)
			)
			(layer "F.Fab")
		)
		(fp_line
			(start 2.549906 -2.549906)
			(end -2.549906 -2.549906)
			(stroke
				(width 0.1)
				(type default)
			)
			(layer "F.Fab")
		)
		(fp_line
			(start -2.549906 2.549906)
			(end 2.549906 2.549906)
			(stroke
				(width 0.1)
				(type default)
			)
			(layer "F.Fab")
		)
		(fp_line
			(start -2.549906 -2.549906)
			(end -2.549906 2.549906)
			(stroke
				(width 0.1)
				(type default)
			)
			(layer "F.Fab")
		)
		(fp_poly
			(pts
				(xy -3.806698 -2.25806) (xy -3.806698 -1.24206) (xy -2.790698 -1.75006)
			)
			(stroke
				(width 0)
				(type default)
			)
			(fill yes)
			(layer "F.Fab")
		)
		(pad "1" smd rect
			(at -2.250186 -1.75006 270)
			(size 0.254 0.3556)
			(layers "F.Cu" "F.Mask" "F.Paste")
			(net "P12V_AUX")
		)
		(pad "2" smd rect
			(at -2.237486 -1.249934 270)
			(size 0.254 0.381)
			(layers "F.Cu" "F.Mask" "F.Paste")
			(net "P12V_AUX")
		)
		(pad "3" smd rect
			(at -2.237486 -0.750062 270)
			(size 0.254 0.381)
			(layers "F.Cu" "F.Mask" "F.Paste")
			(net "HSC_D_OC_3")
		)
		(pad "4" smd rect
			(at -2.237486 -0.249936 270)
			(size 0.254 0.381)
			(layers "F.Cu" "F.Mask" "F.Paste")
			(net "HSC_ON")
		)
		(pad "5" smd rect
			(at -2.237486 0.249936 270)
			(size 0.254 0.381)
			(layers "F.Cu" "F.Mask" "F.Paste")
			(net "HSC_FAULT")
		)
		(pad "6" smd rect
			(at -2.237486 0.750062 270)
			(size 0.254 0.381)
			(layers "F.Cu" "F.Mask" "F.Paste")
			(net "HSC_FLT_TYPE_3")
		)
		(pad "7" smd rect
			(at -2.237486 1.249934 270)
			(size 0.254 0.381)
			(layers "F.Cu" "F.Mask" "F.Paste")
			(net "HSC_NC1_3")
		)
		(pad "8" smd rect
			(at -2.250186 1.75006 270)
			(size 0.254 0.3556)
			(layers "F.Cu" "F.Mask" "F.Paste")
			(net "HSC_MODE_3")
		)
		(pad "9" smd rect
			(at -1.75006 2.250186 180)
			(size 0.254 0.3556)
			(layers "F.Cu" "F.Mask" "F.Paste")
			(net "P12V_PSU")
		)
		(pad "10" smd rect
			(at -1.249934 2.237486 180)
			(size 0.254 0.381)
			(layers "F.Cu" "F.Mask" "F.Paste")
			(net "P12V_PSU")
		)
		(pad "11" smd rect
			(at -0.750062 2.237486 180)
			(size 0.254 0.381)
			(layers "F.Cu" "F.Mask" "F.Paste")
			(net "P12V_PSU")
		)
		(pad "12" smd rect
			(at -0.249936 2.237486 180)
			(size 0.254 0.381)
			(layers "F.Cu" "F.Mask" "F.Paste")
			(net "P12V_PSU")
		)
		(pad "13" smd rect
			(at 0.249936 2.237486 180)
			(size 0.254 0.381)
			(layers "F.Cu" "F.Mask" "F.Paste")
			(net "P12V_PSU")
		)
		(pad "14" smd rect
			(at 0.750062 2.237486 180)
			(size 0.254 0.381)
			(layers "F.Cu" "F.Mask" "F.Paste")
			(net "P12V_PSU")
		)
		(pad "15" smd rect
			(at 1.249934 2.237486 180)
			(size 0.254 0.381)
			(layers "F.Cu" "F.Mask" "F.Paste")
			(net "P12V_PSU")
		)
		(pad "16" smd rect
			(at 1.75006 2.250186 180)
			(size 0.254 0.3556)
			(layers "F.Cu" "F.Mask" "F.Paste")
			(net "P12V_PSU")
		)
		(pad "17" smd rect
			(at 2.250186 1.75006 270)
			(size 0.254 0.3556)
			(layers "F.Cu" "F.Mask" "F.Paste")
			(net "HSC_SCREF_3")
		)
		(pad "18" smd rect
			(at 2.237486 1.249934 270)
			(size 0.254 0.381)
			(layers "F.Cu" "F.Mask" "F.Paste")
			(net "HSC_VTEMP")
		)
		(pad "19" smd rect
			(at 2.237486 0.750062 270)
			(size 0.254 0.381)
			(layers "F.Cu" "F.Mask" "F.Paste")
			(net "HSC_SS")
		)
		(pad "20" smd rect
			(at 2.237486 0.249936 270)
			(size 0.254 0.381)
			(layers "F.Cu" "F.Mask" "F.Paste")
			(net "AGND_HSC")
		)
		(pad "21" smd rect
			(at 2.237486 -0.249936 270)
			(size 0.254 0.381)
			(layers "F.Cu" "F.Mask" "F.Paste")
			(net "HSC_VDD_R_3")
		)
		(pad "22" smd rect
			(at 2.237486 -0.750062 270)
			(size 0.254 0.381)
			(layers "F.Cu" "F.Mask" "F.Paste")
			(net "HSC_IMON")
		)
		(pad "23" smd rect
			(at 2.237486 -1.249934 270)
			(size 0.254 0.381)
			(layers "F.Cu" "F.Mask" "F.Paste")
			(net "HSC_CS_3")
		)
		(pad "24" smd rect
			(at 2.250186 -1.75006 270)
			(size 0.254 0.3556)
			(layers "F.Cu" "F.Mask" "F.Paste")
			(net "HSC_OCREF")
		)
		(pad "25" smd rect
			(at 1.75006 -2.250186 180)
			(size 0.254 0.3556)
			(layers "F.Cu" "F.Mask" "F.Paste")
			(net "P12V_AUX")
		)
		(pad "26" smd rect
			(at 1.249934 -2.237486 180)
			(size 0.254 0.381)
			(layers "F.Cu" "F.Mask" "F.Paste")
			(net "P12V_AUX")
		)
		(pad "27" smd rect
			(at 0.750062 -2.237486 180)
			(size 0.254 0.381)
			(layers "F.Cu" "F.Mask" "F.Paste")
			(net "P12V_AUX")
		)
		(pad "28" smd rect
			(at 0.249936 -2.237486 180)
			(size 0.254 0.381)
			(layers "F.Cu" "F.Mask" "F.Paste")
			(net "P12V_AUX")
		)
		(pad "29" smd rect
			(at -0.249936 -2.237486 180)
			(size 0.254 0.381)
			(layers "F.Cu" "F.Mask" "F.Paste")
			(net "P12V_AUX")
		)
		(pad "30" smd rect
			(at -0.750062 -2.237486 180)
			(size 0.254 0.381)
			(layers "F.Cu" "F.Mask" "F.Paste")
			(net "P12V_AUX")
		)
		(pad "31" smd rect
			(at -1.249934 -2.237486 180)
			(size 0.254 0.381)
			(layers "F.Cu" "F.Mask" "F.Paste")
			(net "P12V_AUX")
		)
		(pad "32" smd rect
			(at -1.75006 -2.250186 180)
			(size 0.254 0.3556)
			(layers "F.Cu" "F.Mask" "F.Paste")
			(net "P12V_AUX")
		)
		(pad "33" smd rect
			(at 0 0 180)
			(size 3.4036 3.4036)
			(layers "F.Cu" "F.Mask" "F.Paste")
			(net "P12V_PSU")
		)
		(zone
			(layer "F.Cu")
			(hatch none 0.5)
			(connect_pads
				(clearance 0)
			)
			(min_thickness 0.25)
			(keepout
				(tracks not_allowed)
				(vias allowed)
				(pads allowed)
				(copperpour not_allowed)
				(footprints allowed)
			)
			(placement
				(enabled no)
				(sheetname "")
			)
			(fill
				(thermal_gap 0.5)
				(thermal_bridge_width 0.5)
				(island_removal_mode 0)
			)
			(polygon
				(pts
					(xy 223.529652 -401.275042) (xy 223.529652 -400.769328) (xy 223.46158 -400.701256) (xy 222.955866 -400.701256)
					(xy 222.955866 -400.726656) (xy 220.060266 -400.726656) (xy 220.060266 -400.701256) (xy 219.48648 -400.701256)
					(xy 219.48648 -401.275042) (xy 219.51188 -401.275042) (xy 219.51188 -404.170642) (xy 219.48648 -404.170642)
					(xy 219.48648 -404.475442) (xy 219.755466 -404.475442) (xy 219.755466 -400.970242) (xy 223.260666 -400.970242)
					(xy 223.260666 -403.230842) (xy 223.504252 -403.230842) (xy 223.504252 -401.275042)
				)
			)
		)
	)
)
